G04*
G04 #@! TF.GenerationSoftware,Altium Limited,Altium Designer,23.6.0 (18)*
G04*
G04 Layer_Physical_Order=1*
G04 Layer_Color=255*
%FSLAX44Y44*%
%MOMM*%
G71*
G04*
G04 #@! TF.SameCoordinates,59133E90-4310-4D8A-9E2C-91A8D2F69FBB*
G04*
G04*
G04 #@! TF.FilePolarity,Positive*
G04*
G01*
G75*
%ADD14R,0.5153X0.4725*%
%ADD15R,0.5000X0.6000*%
%ADD16R,0.6000X0.5500*%
%ADD17R,0.6153X0.5725*%
%ADD18R,1.7062X1.1546*%
%ADD19R,1.1000X1.1000*%
%ADD20R,0.8000X1.5000*%
%ADD21R,1.5000X0.8000*%
%ADD22R,0.8000X0.8000*%
%ADD23R,0.9000X0.8000*%
%ADD24R,4.9000X1.1000*%
G04:AMPARAMS|DCode=25|XSize=0.4mm|YSize=0.85mm|CornerRadius=0.05mm|HoleSize=0mm|Usage=FLASHONLY|Rotation=180.000|XOffset=0mm|YOffset=0mm|HoleType=Round|Shape=RoundedRectangle|*
%AMROUNDEDRECTD25*
21,1,0.4000,0.7500,0,0,180.0*
21,1,0.3000,0.8500,0,0,180.0*
1,1,0.1000,-0.1500,0.3750*
1,1,0.1000,0.1500,0.3750*
1,1,0.1000,0.1500,-0.3750*
1,1,0.1000,-0.1500,-0.3750*
%
%ADD25ROUNDEDRECTD25*%
G04:AMPARAMS|DCode=26|XSize=0.3mm|YSize=0.8mm|CornerRadius=0.0495mm|HoleSize=0mm|Usage=FLASHONLY|Rotation=0.000|XOffset=0mm|YOffset=0mm|HoleType=Round|Shape=RoundedRectangle|*
%AMROUNDEDRECTD26*
21,1,0.3000,0.7010,0,0,0.0*
21,1,0.2010,0.8000,0,0,0.0*
1,1,0.0990,0.1005,-0.3505*
1,1,0.0990,-0.1005,-0.3505*
1,1,0.0990,-0.1005,0.3505*
1,1,0.0990,0.1005,0.3505*
%
%ADD26ROUNDEDRECTD26*%
%ADD27R,0.5725X0.6153*%
%ADD28R,1.0500X2.2000*%
%ADD29R,1.0000X1.0500*%
%ADD30R,0.3627X0.4541*%
%ADD31R,0.8500X0.6500*%
%ADD32R,0.6000X0.5000*%
%ADD33R,0.5811X0.4725*%
%ADD34R,0.4725X0.5811*%
%ADD35R,0.5500X0.6000*%
%ADD36R,0.3500X1.4500*%
%ADD37R,1.1546X1.7062*%
%ADD51C,0.1608*%
%ADD52C,0.1778*%
%ADD53C,0.3048*%
%ADD54C,0.2540*%
%ADD55C,0.5080*%
%ADD56C,0.1905*%
%ADD57C,0.3810*%
%ADD58C,0.4064*%
%ADD59C,5.5000*%
G36*
X215922Y318370D02*
X201230D01*
Y307830D01*
X201230D01*
Y307370D01*
X201230D01*
Y296830D01*
X201230D01*
Y296370D01*
X201230D01*
Y285830D01*
X201230D01*
Y285370D01*
X201230D01*
Y274830D01*
X201230D01*
Y274370D01*
X201230D01*
Y263830D01*
X201230D01*
Y263370D01*
X201230D01*
Y252830D01*
X215922D01*
Y241370D01*
X201230D01*
Y230830D01*
X201230D01*
Y230370D01*
X201230D01*
Y219830D01*
X201230D01*
Y219370D01*
X201230D01*
Y208830D01*
X201230D01*
Y208370D01*
X201230D01*
Y197830D01*
X201230D01*
Y197370D01*
X201230D01*
Y186830D01*
X201230D01*
Y186370D01*
X201230D01*
Y175830D01*
X215922D01*
X215922Y43376D01*
X213382Y42066D01*
X211970Y42943D01*
X211801Y44197D01*
X211801Y44264D01*
X211801Y44462D01*
Y58285D01*
X192199D01*
Y44199D01*
X199884D01*
X200633Y42905D01*
X201091Y41659D01*
X200698Y40710D01*
Y39397D01*
X201201Y38183D01*
X202130Y37254D01*
X203343Y36752D01*
X204657D01*
X205507Y37104D01*
X205901Y37248D01*
X208331Y36755D01*
X208558Y36543D01*
X208793Y35190D01*
X208626Y33663D01*
X208588Y33541D01*
X207209Y32162D01*
X207209Y32162D01*
X206767Y31500D01*
X188553D01*
Y44329D01*
X188620D01*
X188193Y48664D01*
X186928Y52833D01*
X184874Y56676D01*
X182111Y60044D01*
X182064Y59997D01*
X182064Y59997D01*
X174513Y67547D01*
X174513Y67547D01*
X174571Y67605D01*
X170707Y70777D01*
X166298Y73133D01*
X161514Y74584D01*
X156539Y75075D01*
Y75075D01*
X154035Y75160D01*
X152114Y75349D01*
X148589Y76419D01*
X145340Y78155D01*
X142503Y80483D01*
X142495Y80495D01*
X142486Y80501D01*
X141469Y82023D01*
X141112Y83818D01*
X141115Y83828D01*
Y107000D01*
X141090Y107122D01*
X141579Y110837D01*
X143060Y114413D01*
X145341Y117385D01*
X145445Y117455D01*
X160224Y132234D01*
X160262Y132197D01*
X163355Y135818D01*
X165843Y139879D01*
X167666Y144279D01*
X168778Y148910D01*
X169151Y153657D01*
X169098D01*
Y163214D01*
X169510Y163830D01*
X176270D01*
Y181370D01*
X165730D01*
X165730Y181370D01*
X165270D01*
Y181370D01*
X163190Y181370D01*
X154730D01*
Y163830D01*
X161991D01*
Y153697D01*
X162009Y153610D01*
X161569Y149149D01*
X160243Y144776D01*
X158089Y140746D01*
X155245Y137281D01*
X155171Y137232D01*
X140411Y122471D01*
X140411Y122471D01*
X140365Y122517D01*
X137638Y119194D01*
X135612Y115403D01*
X134364Y111290D01*
X133943Y107012D01*
X134008D01*
X134008Y107012D01*
Y83804D01*
X133947D01*
X134350Y80744D01*
X135531Y77893D01*
X135969Y77322D01*
X137433Y75388D01*
Y75388D01*
X141358Y72167D01*
X145836Y69773D01*
X150695Y68299D01*
X155749Y67801D01*
Y67801D01*
X158254Y67716D01*
X160099Y67535D01*
X163546Y66489D01*
X166722Y64791D01*
X169501Y62511D01*
X169505Y62505D01*
X177005Y55005D01*
X176996Y54995D01*
X178880Y52699D01*
X180280Y50080D01*
X181142Y47238D01*
X181433Y44282D01*
X181447D01*
Y31500D01*
X175948D01*
X175902Y31731D01*
X175007Y33894D01*
X174123Y35217D01*
X172467Y36872D01*
X171144Y37757D01*
X171144Y37757D01*
X168981Y38652D01*
X168981Y38653D01*
X167421Y38963D01*
X165079D01*
X163519Y38653D01*
X163519Y38652D01*
X161356Y37757D01*
X160033Y36872D01*
X158377Y35217D01*
X157493Y33894D01*
X157493Y33894D01*
X156597Y31731D01*
X156552Y31500D01*
X119766D01*
Y52564D01*
Y56402D01*
X119724Y56614D01*
X119382Y59209D01*
X118395Y61592D01*
X118299Y61824D01*
X116970Y63562D01*
X116270Y65848D01*
X116220Y66098D01*
X116266Y66332D01*
Y69480D01*
X118020D01*
Y77980D01*
Y86520D01*
X116266D01*
Y135950D01*
X116870Y136201D01*
X117799Y137130D01*
X118302Y138343D01*
Y139657D01*
X117799Y140870D01*
X116870Y141799D01*
X115657Y142302D01*
X114343D01*
X113130Y141799D01*
X112201Y140870D01*
X111698Y139657D01*
Y138343D01*
X111852Y137972D01*
X111734Y137381D01*
Y88334D01*
X109980Y86520D01*
X108020D01*
Y86520D01*
X99980D01*
Y77980D01*
Y69480D01*
X101750D01*
X102156Y66399D01*
X103387Y63425D01*
X103646Y63088D01*
Y61815D01*
X104149Y60602D01*
X105078Y59673D01*
X106292Y59170D01*
X107605D01*
X108819Y59673D01*
X109748Y60602D01*
X110186Y61660D01*
X110759Y61855D01*
X112790Y62010D01*
X113037Y61415D01*
X113427Y60921D01*
X114792Y58946D01*
X114848Y58863D01*
X115286Y56663D01*
X115234Y56402D01*
Y52564D01*
Y31500D01*
X39766D01*
Y37561D01*
X70602Y68398D01*
X71094Y69133D01*
X71266Y70000D01*
Y72480D01*
X73020D01*
Y82984D01*
X76980D01*
Y72480D01*
X77709D01*
X78166Y69940D01*
X77713Y69486D01*
X77210Y68273D01*
Y66959D01*
X77713Y65745D01*
X78642Y64817D01*
X79855Y64314D01*
X81169D01*
X82382Y64817D01*
X83311Y65745D01*
X83814Y66959D01*
Y68273D01*
X83311Y69486D01*
X83022Y69776D01*
Y72480D01*
X85020D01*
Y82984D01*
X88083D01*
X88292Y82775D01*
X89506Y82272D01*
X90819D01*
X92033Y82775D01*
X92962Y83704D01*
X93464Y84917D01*
Y86231D01*
X92962Y87444D01*
X92033Y88373D01*
X90819Y88876D01*
X89506D01*
X88292Y88373D01*
X87560Y87641D01*
X85020Y87818D01*
Y89520D01*
X76980D01*
Y87516D01*
X73020D01*
Y89520D01*
X64980D01*
Y80980D01*
Y72480D01*
X64980D01*
X65735Y69940D01*
X37603Y41808D01*
X35679Y43295D01*
X36182Y44509D01*
Y45823D01*
X35679Y47036D01*
X35041Y48465D01*
X35799Y49775D01*
X36302Y50988D01*
Y52302D01*
X35799Y53516D01*
X34870Y54444D01*
X33657Y54947D01*
X32343D01*
X31130Y54444D01*
X30201Y53516D01*
X29698Y52302D01*
Y50988D01*
X30201Y49775D01*
X30840Y48346D01*
X30081Y47036D01*
X29578Y45823D01*
Y44509D01*
X30081Y43295D01*
X30209Y43167D01*
X30793Y41664D01*
X30259Y39928D01*
X30201Y39870D01*
X29698Y38657D01*
Y37343D01*
X30201Y36130D01*
X30850Y34500D01*
X30201Y32870D01*
X29698Y31657D01*
Y31500D01*
X13233D01*
X12791Y32162D01*
X11412Y33541D01*
X11412Y33541D01*
X10088Y34425D01*
X10088Y34425D01*
X8286Y35172D01*
X7699Y35289D01*
X7125Y35463D01*
X6150Y35559D01*
X4078Y37200D01*
X4078Y175830D01*
X19770D01*
Y186370D01*
X19770D01*
Y186830D01*
X19770D01*
Y197370D01*
X19770D01*
Y197830D01*
X19770D01*
Y208370D01*
X19770D01*
Y208830D01*
X19770D01*
Y219370D01*
X19770D01*
Y219830D01*
X19770D01*
Y230370D01*
X19770D01*
Y230830D01*
X19770D01*
Y241370D01*
X19770D01*
Y241830D01*
X19770D01*
Y252370D01*
X19770D01*
Y252830D01*
X19770D01*
Y263370D01*
X19770D01*
Y263830D01*
X19770D01*
Y274370D01*
X19770D01*
Y274830D01*
X19770D01*
Y285370D01*
X19770D01*
Y285830D01*
X19770D01*
Y296370D01*
X19770D01*
Y296830D01*
X19770D01*
Y307370D01*
X19770D01*
Y307830D01*
X19770D01*
Y318370D01*
X4078D01*
X4078Y415922D01*
X25140D01*
X26939Y414132D01*
X26939Y413382D01*
X26939Y405868D01*
X26325Y404809D01*
X25419Y403972D01*
X25166Y403860D01*
X24043Y404325D01*
X22729D01*
X22607Y404274D01*
X20230Y403377D01*
X19301Y404306D01*
X18087Y404809D01*
X16774D01*
X15560Y404306D01*
X14631Y403377D01*
X14128Y402164D01*
Y400850D01*
X14631Y399637D01*
X15280Y398988D01*
X15615Y398203D01*
X15832Y396194D01*
X15695Y395505D01*
Y388495D01*
X15832Y387806D01*
X16222Y387223D01*
X16806Y386832D01*
X17495Y386695D01*
X19505D01*
X20194Y386832D01*
X20777Y387223D01*
X21223D01*
X21806Y386832D01*
X22495Y386695D01*
X24505D01*
X25194Y386832D01*
X26000Y387138D01*
X26806Y386832D01*
X27495Y386695D01*
X29505D01*
X30194Y386832D01*
X30362Y386945D01*
X31465Y387044D01*
X33313Y386565D01*
X33398Y386439D01*
X34439Y385398D01*
X35174Y384906D01*
X36042Y384734D01*
X41195D01*
Y381730D01*
X41333Y381039D01*
X41724Y380454D01*
X42309Y380063D01*
X43000Y379925D01*
X46000D01*
X46691Y380063D01*
X47276Y380454D01*
X47667Y381039D01*
X47805Y381730D01*
Y389230D01*
X47667Y389921D01*
X47276Y390506D01*
X46691Y390897D01*
X46000Y391035D01*
X43000D01*
X42309Y390897D01*
X41724Y390506D01*
X41333Y389921D01*
X41203Y389266D01*
X37266D01*
Y390959D01*
X37094Y391826D01*
X36602Y392561D01*
X35561Y393602D01*
X34826Y394094D01*
X33958Y394266D01*
X31305D01*
Y395505D01*
X31168Y396194D01*
X30777Y396777D01*
X30194Y397168D01*
X29505Y397305D01*
X28905Y397897D01*
X28345Y399363D01*
X28674Y399643D01*
X29731Y400307D01*
X30757Y399882D01*
X32071D01*
X33284Y400385D01*
X34213Y401314D01*
X34716Y402527D01*
Y403707D01*
X35632Y405868D01*
X37710Y406984D01*
X41195D01*
Y404230D01*
X41333Y403539D01*
X41724Y402954D01*
X42309Y402563D01*
X43000Y402425D01*
X46000D01*
X46691Y402563D01*
X47276Y402954D01*
X47667Y403539D01*
X47805Y404230D01*
Y411730D01*
X47667Y412421D01*
X47276Y413006D01*
X46691Y413397D01*
X47019Y415922D01*
X54981D01*
X55309Y413397D01*
X54724Y413006D01*
X54333Y412421D01*
X54195Y411730D01*
Y404230D01*
X54333Y403539D01*
X54724Y402954D01*
X55309Y402563D01*
X56000Y402425D01*
X59000D01*
X59691Y402563D01*
X60276Y402954D01*
X60667Y403539D01*
X60783Y404123D01*
X64672D01*
X65411Y403384D01*
Y402630D01*
X65914Y401416D01*
X66843Y400487D01*
X68057Y399985D01*
X68811D01*
X84398Y384398D01*
X85133Y383906D01*
X86000Y383734D01*
X90061D01*
X94230Y379565D01*
Y379510D01*
X94000Y379000D01*
Y359034D01*
X91563Y357770D01*
X89737Y358611D01*
Y368980D01*
X90770D01*
Y377520D01*
X83310D01*
X83230Y377520D01*
X80770D01*
X80690Y377520D01*
X73230D01*
X71118Y378554D01*
X70266Y379262D01*
Y384958D01*
X70093Y385826D01*
X69602Y386561D01*
X68561Y387602D01*
X67826Y388093D01*
X66958Y388266D01*
X60805D01*
Y389230D01*
X60667Y389921D01*
X60276Y390506D01*
X59691Y390897D01*
X59000Y391035D01*
X56000D01*
X55309Y390897D01*
X54724Y390506D01*
X54333Y389921D01*
X54195Y389230D01*
Y381730D01*
X54333Y381039D01*
X54724Y380454D01*
X55309Y380063D01*
X56000Y379925D01*
X59000D01*
X59691Y380063D01*
X60276Y380454D01*
X60667Y381039D01*
X60805Y381730D01*
Y383734D01*
X65734D01*
Y376870D01*
X62480D01*
Y369606D01*
X70831D01*
Y369606D01*
X73230Y369266D01*
Y368980D01*
X80690D01*
X80770Y368980D01*
X83263Y368866D01*
Y357270D01*
X80230D01*
Y346730D01*
X87192D01*
X88211Y345711D01*
X89261Y345009D01*
X90500Y344763D01*
X94230D01*
Y341230D01*
X145770D01*
Y354770D01*
X145500D01*
Y369230D01*
X145770D01*
Y370115D01*
X148724D01*
Y364059D01*
X148878Y363288D01*
Y360519D01*
X155045D01*
Y361182D01*
X158246D01*
Y360647D01*
X168734D01*
Y357632D01*
X166868D01*
Y348939D01*
Y340368D01*
X168734D01*
Y330370D01*
X165730D01*
Y312830D01*
X176270D01*
Y330370D01*
X173266D01*
Y340368D01*
X175132D01*
Y348939D01*
Y357632D01*
X173266D01*
Y360647D01*
X175511D01*
Y368912D01*
X175511D01*
X176315Y371119D01*
X176815D01*
Y380159D01*
X173561D01*
Y382854D01*
X177574D01*
Y395894D01*
X165034D01*
Y382854D01*
X169029D01*
Y380159D01*
X165775D01*
Y371119D01*
X165775D01*
X164971Y368912D01*
X158246D01*
Y367657D01*
X155199D01*
Y373038D01*
X154952Y374277D01*
X154777Y374539D01*
X154589Y375487D01*
X153747Y376747D01*
X152487Y377589D01*
X151000Y377885D01*
X145770D01*
Y382770D01*
X97435D01*
X92602Y387602D01*
X91867Y388093D01*
X91000Y388266D01*
X86939D01*
X72015Y403189D01*
Y403943D01*
X71513Y405157D01*
X70584Y406086D01*
X69370Y406589D01*
X68616D01*
X67213Y407991D01*
X66478Y408483D01*
X65611Y408655D01*
X60805D01*
Y411730D01*
X60667Y412421D01*
X60276Y413006D01*
X59691Y413397D01*
X60019Y415922D01*
X215922D01*
X215922Y318370D01*
D02*
G37*
%LPC*%
G36*
X29505Y365305D02*
X27495D01*
X26806Y365168D01*
X26000Y364862D01*
X25194Y365168D01*
X24505Y365305D01*
X22495D01*
X21806Y365168D01*
X21223Y364777D01*
X20777D01*
X20194Y365168D01*
X19505Y365305D01*
X17495D01*
X16806Y365168D01*
X16000Y364862D01*
X15194Y365168D01*
X14505Y365305D01*
X12495D01*
X11806Y365168D01*
X11222Y364777D01*
X10832Y364194D01*
X10696Y363505D01*
Y356495D01*
X10832Y355806D01*
X11164Y355310D01*
X10669Y352770D01*
X6730D01*
Y345230D01*
X6730D01*
Y342770D01*
X6730D01*
Y335230D01*
X15270D01*
Y336734D01*
X21730D01*
Y335230D01*
X30270D01*
Y342770D01*
X30270D01*
Y345230D01*
X30270D01*
Y352770D01*
X30270Y352770D01*
X30664Y355147D01*
X30777Y355223D01*
X31168Y355806D01*
X31305Y356495D01*
Y357968D01*
X33374Y358744D01*
X35868Y357599D01*
Y349939D01*
X44132D01*
Y358632D01*
X44132Y358632D01*
X43115Y361172D01*
X43126Y361198D01*
Y362512D01*
X42623Y363726D01*
X41694Y364655D01*
X40480Y365157D01*
X39167D01*
X37953Y364655D01*
X37452Y364153D01*
X31176D01*
X31168Y364194D01*
X30777Y364777D01*
X30194Y365168D01*
X29505Y365305D01*
D02*
G37*
G36*
X71770Y366770D02*
X60230D01*
Y364090D01*
X55302D01*
X54311Y363893D01*
X54218Y363831D01*
X50368D01*
Y355480D01*
Y348169D01*
X52503D01*
Y345090D01*
X51476D01*
X50485Y344893D01*
X50127Y344654D01*
X49258D01*
X48045Y344151D01*
X47116Y343222D01*
X46613Y342008D01*
Y340695D01*
X47116Y339481D01*
X48045Y338552D01*
X49258Y338050D01*
X50572D01*
X51786Y338552D01*
X52715Y339481D01*
X52892Y339910D01*
X60230D01*
Y337230D01*
X71770D01*
Y347770D01*
X60230D01*
Y345090D01*
X57682D01*
Y351252D01*
X57632Y351502D01*
Y358910D01*
X60230D01*
Y356230D01*
X71770D01*
Y366770D01*
D02*
G37*
G36*
X149680Y337477D02*
X148367D01*
X147153Y336975D01*
X146224Y336046D01*
X145722Y334832D01*
Y333518D01*
X145822Y333275D01*
X144534Y331031D01*
X142329Y331077D01*
X141125Y332657D01*
Y333970D01*
X140622Y335184D01*
X139693Y336113D01*
X138480Y336616D01*
X137166D01*
X135952Y336113D01*
X135023Y335184D01*
X134521Y333970D01*
Y332657D01*
X133600Y331448D01*
X132566Y331226D01*
X131790Y331362D01*
X130211Y333375D01*
Y334688D01*
X129708Y335902D01*
X128779Y336831D01*
X127566Y337334D01*
X126252D01*
X125039Y336831D01*
X124110Y335902D01*
X123607Y334688D01*
Y333375D01*
X123799Y332910D01*
X122829Y330886D01*
X122312Y330370D01*
X119190Y330370D01*
X110730Y330370D01*
X108190Y330370D01*
X99730Y330370D01*
X97190Y330370D01*
X88730Y330370D01*
X86190Y330370D01*
X77730Y330370D01*
X75190Y330370D01*
X66730D01*
Y312830D01*
X75190D01*
X77270Y312830D01*
X79810Y312830D01*
X88270Y312830D01*
X90810Y312830D01*
X99270Y312830D01*
X101810Y312830D01*
X110270Y312830D01*
X112810Y312830D01*
X121270Y312830D01*
X123810Y312830D01*
X132270Y312830D01*
X134810Y312830D01*
X143270Y312830D01*
X145810Y312830D01*
X154270D01*
Y330370D01*
X153480D01*
X152910Y331036D01*
X152074Y332910D01*
X152326Y333518D01*
Y334832D01*
X151823Y336046D01*
X150894Y336975D01*
X149680Y337477D01*
D02*
G37*
G36*
X55270Y330370D02*
X44730D01*
Y312830D01*
X55270D01*
Y330370D01*
D02*
G37*
G36*
X121730Y181370D02*
X119190Y181370D01*
X110730Y181370D01*
X108190Y181370D01*
X99730Y181370D01*
X97190Y181370D01*
X88730D01*
Y163830D01*
X90115D01*
Y158858D01*
X87962D01*
Y155417D01*
X87923Y155226D01*
X87946Y155114D01*
Y146884D01*
X88242Y145397D01*
X89084Y144137D01*
X90344Y143295D01*
X91831Y142999D01*
X93317Y143295D01*
X94577Y144137D01*
X95420Y145397D01*
X95715Y146884D01*
Y154122D01*
X96747Y154812D01*
X97589Y156072D01*
X97885Y157559D01*
Y162153D01*
X99730Y163830D01*
X100497D01*
X102293Y162034D01*
Y155037D01*
X102330Y154852D01*
Y147185D01*
X102293Y147000D01*
X102589Y145513D01*
X103431Y144253D01*
X104691Y143411D01*
X106178Y143115D01*
X107664Y143411D01*
X108925Y144253D01*
X108961Y144290D01*
X109803Y145550D01*
X110099Y147037D01*
Y155000D01*
X110062Y155185D01*
Y161567D01*
X110730Y163830D01*
X112810Y163830D01*
X121270Y163830D01*
X123115Y162153D01*
Y139214D01*
X123411Y137728D01*
X124253Y136468D01*
X125468Y135253D01*
X126728Y134411D01*
X128214Y134115D01*
X129701Y134411D01*
X130961Y135253D01*
X131803Y136513D01*
X132099Y138000D01*
X131934Y138828D01*
X132061Y141368D01*
X132061Y141368D01*
Y148632D01*
X130885D01*
Y151368D01*
X132061D01*
Y158632D01*
X130885D01*
Y163830D01*
X132270D01*
Y181370D01*
X121730Y181370D01*
D02*
G37*
G36*
X66730D02*
X64190Y181370D01*
X55730Y181370D01*
X53190Y181370D01*
X44730Y181370D01*
X42190Y181370D01*
X33730D01*
Y163830D01*
X42190D01*
X44270Y163830D01*
X46810Y163830D01*
X55270Y163830D01*
X57810Y163830D01*
X66270Y163830D01*
X68810Y163830D01*
X77270D01*
Y181370D01*
X66730Y181370D01*
D02*
G37*
G36*
X65230Y144270D02*
X62770D01*
X62690Y144270D01*
X55230D01*
Y142849D01*
X52102D01*
X51576Y142744D01*
X51445D01*
X51324Y142694D01*
X51012Y142632D01*
X50747Y142455D01*
X50232Y142241D01*
X49303Y141313D01*
X48800Y140099D01*
Y138785D01*
X49303Y137572D01*
X50232Y136643D01*
X51445Y136140D01*
X52759D01*
X55230Y135730D01*
Y135730D01*
X62690D01*
X62770Y135730D01*
X65230D01*
X66734Y133780D01*
Y130632D01*
X63939D01*
Y123368D01*
X71632D01*
Y124734D01*
X74379D01*
X74740Y124373D01*
X75954Y123870D01*
X77268D01*
X78481Y124373D01*
X79410Y125302D01*
X79913Y126515D01*
Y127829D01*
X79410Y129043D01*
X78481Y129972D01*
X77268Y130474D01*
X75954D01*
X74740Y129972D01*
X74172Y129403D01*
X71632Y129598D01*
Y130632D01*
X71266D01*
Y135730D01*
X72770D01*
Y144270D01*
X65310D01*
X65230Y144270D01*
D02*
G37*
G36*
X87520Y116020D02*
X70480D01*
Y115386D01*
X67940Y114730D01*
X67870Y114799D01*
X66657Y115302D01*
X65343D01*
X64130Y114799D01*
X63201Y113870D01*
X62698Y112657D01*
Y111343D01*
X63201Y110130D01*
X64130Y109201D01*
X65343Y108698D01*
X66657D01*
X67870Y109201D01*
X67940Y109270D01*
X70480Y108615D01*
Y107980D01*
X87520D01*
Y109734D01*
X92608D01*
X92923Y109419D01*
X94137Y108917D01*
X95450D01*
X96664Y109419D01*
X97593Y110348D01*
X98095Y111562D01*
Y112875D01*
X97593Y114089D01*
X96664Y115018D01*
X95450Y115521D01*
X94137D01*
X92923Y115018D01*
X92171Y114266D01*
X87520D01*
Y116020D01*
D02*
G37*
G36*
X38149Y122598D02*
X27608D01*
Y112058D01*
X38149D01*
Y112637D01*
X38635Y113132D01*
X40689Y114125D01*
X41135Y113940D01*
X42449D01*
X43663Y114442D01*
X44591Y115371D01*
X45094Y116585D01*
Y117898D01*
X44591Y119112D01*
X43663Y120041D01*
X42449Y120544D01*
X41135D01*
X40689Y120358D01*
X38149Y121394D01*
Y122598D01*
D02*
G37*
G36*
X25770Y135270D02*
X18230D01*
Y130759D01*
X17486Y130014D01*
X16868Y129090D01*
X16651Y128000D01*
X16651Y128000D01*
Y122598D01*
X12608D01*
Y112058D01*
X23148D01*
Y122598D01*
X22349D01*
Y126730D01*
X25770D01*
Y135270D01*
D02*
G37*
G36*
X168657Y134302D02*
X167343D01*
X166130Y133799D01*
X165201Y132870D01*
X164698Y131657D01*
Y130903D01*
X155398Y121602D01*
X154906Y120867D01*
X154734Y120000D01*
Y113000D01*
X154906Y112133D01*
X155398Y111398D01*
X161398Y105398D01*
X162133Y104906D01*
X163000Y104734D01*
X171046D01*
X171230Y102270D01*
X171230Y102194D01*
Y101463D01*
X168770Y101270D01*
Y101270D01*
X161230D01*
Y92730D01*
X168770D01*
Y92730D01*
X171230Y92537D01*
Y91730D01*
X181770D01*
Y102194D01*
X181770Y102270D01*
X181954Y104734D01*
X186046D01*
X186230Y102270D01*
X186230D01*
Y91730D01*
X196770D01*
Y102270D01*
X195767D01*
X193766Y103500D01*
X193594Y104367D01*
X193102Y105102D01*
X189602Y108602D01*
X188867Y109094D01*
X188309Y110455D01*
X189784Y112734D01*
X199061D01*
X200698Y111097D01*
Y110343D01*
X201201Y109130D01*
X202130Y108201D01*
X203343Y107698D01*
X204657D01*
X205870Y108201D01*
X206799Y109130D01*
X207302Y110343D01*
Y111657D01*
X206799Y112870D01*
X205870Y113799D01*
X204657Y114302D01*
X203903D01*
X203495Y114710D01*
X202871Y117201D01*
X203799Y118130D01*
X204302Y119343D01*
Y120657D01*
X203799Y121870D01*
X202870Y122799D01*
X201657Y123302D01*
X200343D01*
X199130Y122799D01*
X198596Y122266D01*
X169404D01*
X168870Y122799D01*
X167657Y123302D01*
X167099D01*
X165869Y125573D01*
X165853Y125649D01*
X167903Y127698D01*
X168657D01*
X169870Y128201D01*
X170799Y129130D01*
X171302Y130343D01*
Y131657D01*
X170799Y132870D01*
X169870Y133799D01*
X168657Y134302D01*
D02*
G37*
G36*
X87520Y105020D02*
X70480D01*
Y103727D01*
X67940Y103087D01*
X67859Y103168D01*
X66645Y103671D01*
X65332D01*
X64118Y103168D01*
X63189Y102240D01*
X62686Y101026D01*
Y99712D01*
X63189Y98499D01*
X64118Y97570D01*
X65332Y97067D01*
X66645D01*
X67859Y97570D01*
X67940Y97651D01*
X70480Y97012D01*
Y96980D01*
X87520D01*
Y99329D01*
X90653D01*
X91187Y98796D01*
X92400Y98293D01*
X93714D01*
X94927Y98796D01*
X95856Y99725D01*
X96359Y100939D01*
Y102252D01*
X95856Y103466D01*
X94927Y104395D01*
X93714Y104897D01*
X92400D01*
X91187Y104395D01*
X90653Y103861D01*
X87520D01*
Y105020D01*
D02*
G37*
G36*
X44801Y77801D02*
X30715D01*
Y58199D01*
X44801D01*
Y77801D01*
D02*
G37*
%LPD*%
D14*
X106214Y155000D02*
D03*
X113786D02*
D03*
X67786Y127000D02*
D03*
X60214D02*
D03*
X135786Y145000D02*
D03*
X128214D02*
D03*
X135786Y155000D02*
D03*
X128214D02*
D03*
X84237Y155226D02*
D03*
X91808D02*
D03*
D15*
X77000Y373250D02*
D03*
X87000D02*
D03*
X165000Y97000D02*
D03*
X155000D02*
D03*
X22000Y131000D02*
D03*
X32000D02*
D03*
X59000Y140000D02*
D03*
X69000D02*
D03*
D16*
X83250Y101000D02*
D03*
X74750D02*
D03*
X83250Y112000D02*
D03*
X74750D02*
D03*
D17*
X162593Y364779D02*
D03*
X171164D02*
D03*
X22714Y410000D02*
D03*
X31286D02*
D03*
D18*
X202000Y51242D02*
D03*
Y76758D02*
D03*
D19*
X184000Y194600D02*
D03*
X163000Y194600D02*
D03*
X142000D02*
D03*
X121000D02*
D03*
X100000D02*
D03*
X79000D02*
D03*
X58000D02*
D03*
X37000D02*
D03*
X184000Y215600D02*
D03*
X163000Y215600D02*
D03*
X142000D02*
D03*
X121000D02*
D03*
X100000D02*
D03*
X79000D02*
D03*
X58000D02*
D03*
X37000D02*
D03*
X184000Y236600D02*
D03*
X163000Y236600D02*
D03*
X142000D02*
D03*
X121000D02*
D03*
X100000D02*
D03*
X79000D02*
D03*
X58000D02*
D03*
X37000D02*
D03*
X184000Y257600D02*
D03*
X163000Y257600D02*
D03*
X142000D02*
D03*
X121000D02*
D03*
X100000D02*
D03*
X79000D02*
D03*
X58000D02*
D03*
X37000D02*
D03*
X184000Y278600D02*
D03*
X163000Y278600D02*
D03*
X142000D02*
D03*
X121000D02*
D03*
X100000D02*
D03*
X79000D02*
D03*
X58000D02*
D03*
X37000D02*
D03*
X184000Y299600D02*
D03*
X163000Y299600D02*
D03*
X142000D02*
D03*
X121000D02*
D03*
X100000D02*
D03*
X79000D02*
D03*
X58000D02*
D03*
X37000D02*
D03*
D20*
X182000Y172600D02*
D03*
X171000D02*
D03*
X160000D02*
D03*
X149000D02*
D03*
X138000D02*
D03*
X127000D02*
D03*
X116000D02*
D03*
X105000D02*
D03*
X94000D02*
D03*
X83000D02*
D03*
X72000D02*
D03*
X61000D02*
D03*
X50000D02*
D03*
X39000D02*
D03*
Y321600D02*
D03*
X50000D02*
D03*
X61000D02*
D03*
X72000D02*
D03*
X83000D02*
D03*
X94000D02*
D03*
X105000D02*
D03*
X116000D02*
D03*
X127000D02*
D03*
X138000D02*
D03*
X149000D02*
D03*
X160000D02*
D03*
X171000D02*
D03*
X182000D02*
D03*
D21*
X11000Y181100D02*
D03*
Y192100D02*
D03*
Y203100D02*
D03*
Y214100D02*
D03*
Y225100D02*
D03*
Y236100D02*
D03*
Y247100D02*
D03*
Y258100D02*
D03*
Y269100D02*
D03*
Y280100D02*
D03*
Y291100D02*
D03*
Y302100D02*
D03*
Y313100D02*
D03*
X210000D02*
D03*
Y258100D02*
D03*
Y269100D02*
D03*
Y302100D02*
D03*
Y291100D02*
D03*
Y280100D02*
D03*
Y247100D02*
D03*
Y236100D02*
D03*
Y225100D02*
D03*
Y214100D02*
D03*
Y203100D02*
D03*
Y192100D02*
D03*
Y181100D02*
D03*
D22*
X191500Y97000D02*
D03*
X176500D02*
D03*
X32878Y117328D02*
D03*
X17879D02*
D03*
D23*
X66000Y361500D02*
D03*
Y342500D02*
D03*
X86000Y352000D02*
D03*
D24*
X120000Y348000D02*
D03*
Y376000D02*
D03*
D25*
X44500Y385480D02*
D03*
X51000D02*
D03*
X57500D02*
D03*
Y407980D02*
D03*
X44500D02*
D03*
D26*
X13500Y360000D02*
D03*
X18500D02*
D03*
X23500D02*
D03*
X28500D02*
D03*
X13500Y392000D02*
D03*
X18500D02*
D03*
X23500D02*
D03*
X28500D02*
D03*
D27*
X171000Y353286D02*
D03*
Y344714D02*
D03*
X40000Y345714D02*
D03*
Y354286D02*
D03*
D28*
X156554Y404624D02*
D03*
X186054D02*
D03*
D29*
X171304Y389374D02*
D03*
D30*
X151962Y357973D02*
D03*
Y364059D02*
D03*
D31*
X171295Y375639D02*
D03*
X183795D02*
D03*
D32*
X11000Y339000D02*
D03*
Y349000D02*
D03*
X26000Y339000D02*
D03*
Y349000D02*
D03*
D33*
X66655Y373238D02*
D03*
X59345D02*
D03*
D34*
X54000Y352345D02*
D03*
Y359655D02*
D03*
D35*
X114000Y73750D02*
D03*
Y82250D02*
D03*
X104000Y73750D02*
D03*
Y82250D02*
D03*
X69000Y85250D02*
D03*
Y76750D02*
D03*
X81000Y85250D02*
D03*
Y76750D02*
D03*
D36*
X17500Y12750D02*
D03*
X22500D02*
D03*
X27500D02*
D03*
X32500D02*
D03*
X37500D02*
D03*
X42500D02*
D03*
X47500D02*
D03*
X52500D02*
D03*
X57500D02*
D03*
X62500D02*
D03*
X67500D02*
D03*
X72500D02*
D03*
X77500D02*
D03*
X82500D02*
D03*
X87500D02*
D03*
X92500D02*
D03*
X97500D02*
D03*
X102500D02*
D03*
X107500D02*
D03*
X112500D02*
D03*
X117500D02*
D03*
X122500D02*
D03*
X127500D02*
D03*
X132500D02*
D03*
X137500D02*
D03*
X142500D02*
D03*
X147500D02*
D03*
X152500D02*
D03*
X187500D02*
D03*
X192500D02*
D03*
X197500D02*
D03*
X202500D02*
D03*
X182500D02*
D03*
X177500D02*
D03*
D37*
X12242Y68000D02*
D03*
X37758D02*
D03*
D51*
X166984Y163879D02*
G03*
X167804Y165859I-1980J1980D01*
G01*
X158729Y133729D02*
G03*
X166984Y153657I-19928J19928D01*
G01*
X143950Y118950D02*
G03*
X139000Y107000I11950J-11950D01*
G01*
Y83828D02*
G03*
X141000Y79000I6828J0D01*
G01*
D02*
G03*
X155780Y72878I14780J14780D01*
G01*
X173018Y66052D02*
G03*
X156539Y72878I-16479J-16479D01*
G01*
X186439Y44329D02*
G03*
X180568Y58502I-20043J0D01*
G01*
X164106Y163879D02*
G03*
X163317Y165783I-2693J0D01*
G01*
X156666Y135736D02*
G03*
X164106Y153697I-17960J17960D01*
G01*
X141906Y120976D02*
G03*
X136122Y107012I13964J-13964D01*
G01*
X136122Y83804D02*
G03*
X138948Y76982I9647J0D01*
G01*
X138987Y76943D02*
G03*
X155749Y70000I16761J16761D01*
G01*
X171000Y64000D02*
G03*
X156515Y70000I-14485J-14485D01*
G01*
X183561Y44282D02*
G03*
X178500Y56500I-17279J0D01*
G01*
X160000Y172600D02*
G03*
X162475Y166625I8450J0D01*
G01*
X170311Y171911D02*
G03*
X167804Y165859I6052J-6052D01*
G01*
X166984Y163879D02*
Y163879D01*
Y163879D02*
Y163879D01*
Y153657D02*
Y163879D01*
X143950Y118950D02*
X158729Y133729D01*
X139000Y83828D02*
Y107000D01*
X155780Y72878D02*
X156539D01*
X173018Y66052D02*
X180568Y58502D01*
X186439Y21222D02*
Y44329D01*
X162475Y166625D02*
X163317Y165783D01*
X164106Y153697D02*
Y163879D01*
X141906Y120976D02*
X156666Y135736D01*
X136122Y83804D02*
Y107012D01*
X138948Y76982D02*
X138987Y76943D01*
X155749Y70000D02*
X156515D01*
X171000Y64000D02*
X178500Y56500D01*
X183561Y21222D02*
Y44282D01*
X170311Y171911D02*
X171000Y172600D01*
X186439Y21222D02*
X186554Y21107D01*
Y13696D02*
Y21107D01*
Y13696D02*
X187500Y12750D01*
X183446Y21107D02*
X183561Y21222D01*
X183446Y13696D02*
Y21107D01*
X182500Y12750D02*
X183446Y13696D01*
D52*
X114000Y66332D02*
G03*
X114984Y62477I8043J0D01*
G01*
X116411Y60589D02*
G03*
X114984Y62477I-7502J-4187D01*
G01*
X117500Y56402D02*
G03*
X116411Y60589I-8592J0D01*
G01*
X104000Y69590D02*
G03*
X106943Y62477I10066J0D01*
G01*
D02*
G03*
X106948Y62472I7123J7113D01*
G01*
D53*
X17879Y117328D02*
X19500Y118950D01*
Y128000D01*
X22000Y130500D01*
Y131000D01*
X190545Y43935D02*
X190820D01*
X192623Y42132D01*
X193937D01*
X197500Y38569D01*
Y12750D02*
Y38569D01*
X52102Y140000D02*
X59000D01*
X52102Y139442D02*
Y140000D01*
X53051Y127000D02*
X60214D01*
X53051Y126729D02*
Y127000D01*
X32878Y117328D02*
X41792D01*
Y117242D02*
Y117328D01*
X32000Y131000D02*
X39452D01*
Y130651D02*
Y131000D01*
D54*
X55092Y342500D02*
X66000D01*
X55092D02*
Y351252D01*
X49915Y341352D02*
X50328D01*
X51476Y342500D01*
X55092D01*
X191000Y28879D02*
Y37000D01*
Y28879D02*
X192500Y27379D01*
Y12750D02*
Y27379D01*
X28500Y360000D02*
Y361334D01*
X28730Y361564D01*
X39532D01*
X39824Y361855D01*
X40000Y361679D01*
Y354286D02*
Y361679D01*
X54000Y352345D02*
X55092Y351252D01*
X55302Y361500D02*
X66000D01*
X63000Y26388D02*
Y38000D01*
X77500Y12750D02*
Y34000D01*
X62500Y12750D02*
Y25888D01*
X63000Y26388D01*
X176000Y43588D02*
X177500Y42088D01*
Y12750D02*
Y42088D01*
X176000Y43588D02*
Y44000D01*
X111000Y34588D02*
Y35000D01*
X107500Y31088D02*
X111000Y34588D01*
X107500Y12750D02*
Y31088D01*
X152000Y36000D02*
X152500Y35500D01*
Y12750D02*
Y35500D01*
X137000Y36000D02*
X137500Y35500D01*
Y12750D02*
Y35500D01*
X122500Y34500D02*
X123000Y35000D01*
X122500Y12750D02*
Y34500D01*
X92500Y33500D02*
X93000Y34000D01*
X92500Y12750D02*
Y33500D01*
X27500Y12750D02*
Y36000D01*
X27000Y12750D02*
X27500D01*
X22500D02*
Y36000D01*
X17500Y12750D02*
Y35000D01*
D55*
X113786Y155000D02*
X115000Y153786D01*
Y146000D02*
Y153786D01*
X106178Y147000D02*
X106214Y147037D01*
Y155000D01*
X135786Y145000D02*
X144847D01*
X145027Y145180D01*
X127000Y139214D02*
Y172600D01*
Y139214D02*
X128214Y138000D01*
X181826Y161442D02*
X182000Y161616D01*
Y172600D01*
X148849Y161221D02*
Y172449D01*
X149000Y172600D01*
X138000D02*
X138262Y172338D01*
Y162104D02*
Y172338D01*
X83000Y172600D02*
X83228Y172372D01*
Y162104D02*
Y172372D01*
X84200Y155189D02*
X84237Y155226D01*
X84200Y147200D02*
Y155189D01*
X83000Y146000D02*
X84200Y147200D01*
X105000Y172600D02*
X106178Y171422D01*
Y155037D02*
Y171422D01*
Y155037D02*
X106214Y155000D01*
X91831Y146884D02*
Y155204D01*
X91808Y155226D02*
X91831Y155204D01*
X94000Y157559D02*
Y172600D01*
X122000Y374000D02*
X151000D01*
X120000Y376000D02*
X122000Y374000D01*
D56*
X69000Y127000D02*
X76611D01*
X114000Y137381D02*
X115000Y138381D01*
Y139000D01*
X114000Y82250D02*
Y137381D01*
X157000Y113000D02*
Y120000D01*
X168000Y131000D01*
X157000Y113000D02*
X163000Y107000D01*
X188000D01*
X191500Y97000D02*
Y103500D01*
X188000Y107000D02*
X191500Y103500D01*
X188000Y115000D02*
X200000D01*
X204000Y111000D01*
X166000Y112000D02*
X185000D01*
X188000Y115000D01*
X167000Y120000D02*
X201000D01*
X155000Y97000D02*
Y105997D01*
X154373D02*
X155000D01*
X165000Y97000D02*
X176500D01*
X69000Y127000D02*
Y140000D01*
X67786Y127000D02*
X69000D01*
X76611D02*
Y127172D01*
X89838Y85250D02*
X90162Y85574D01*
X81000Y85250D02*
X89838D01*
X69000D02*
X81000D01*
X69000Y70000D02*
Y76750D01*
X37500Y38500D02*
X69000Y70000D01*
X37500Y12750D02*
Y38500D01*
X80756Y76506D02*
X81000Y76750D01*
X80756Y67860D02*
Y76506D01*
X80512Y67616D02*
X80756Y67860D01*
X117500Y52564D02*
Y56402D01*
Y12750D02*
Y52564D01*
X114000Y66332D02*
Y73750D01*
X104000Y69590D02*
Y73750D01*
Y82250D02*
X114000D01*
X83845Y101595D02*
X93057D01*
X83250Y101000D02*
X83845Y101595D01*
X94575Y112000D02*
X94793Y112219D01*
X83250Y112000D02*
X94575D01*
X65988Y100369D02*
X74119D01*
X74750Y101000D01*
X66000Y112000D02*
X74750D01*
X149000Y334152D02*
X149024Y334175D01*
X149000Y321600D02*
Y334152D01*
X137823Y333314D02*
X138000Y333136D01*
Y321600D02*
Y333136D01*
X126909Y334032D02*
X127000Y333941D01*
Y321600D02*
Y333941D01*
X68713Y403287D02*
X86000Y386000D01*
X65611Y406389D02*
X68713Y403287D01*
X18500Y392000D02*
Y399819D01*
X17430Y400888D02*
X18500Y399819D01*
X17430Y400888D02*
Y401507D01*
X22592Y409878D02*
X22714Y410000D01*
X14291Y409878D02*
X22592D01*
X11151Y401828D02*
X13500Y399480D01*
Y392000D02*
Y399480D01*
X23386Y401023D02*
X23500Y400909D01*
Y392000D02*
Y400909D01*
X101000Y376000D02*
X120000D01*
X91000Y386000D02*
X101000Y376000D01*
X86000Y386000D02*
X91000D01*
X57500Y407500D02*
Y409250D01*
Y407500D02*
X58611Y406389D01*
X65611D01*
X51000Y371000D02*
X54000Y374000D01*
X59345D01*
X50396Y377474D02*
X51000Y378078D01*
Y386750D01*
X58250Y386000D02*
X66958D01*
X66655Y374000D02*
X68000Y375345D01*
Y384958D01*
X66958Y386000D02*
X68000Y384958D01*
X57500Y386750D02*
X58250Y386000D01*
X35000Y388041D02*
Y390959D01*
X44250Y387000D02*
X44500Y386750D01*
X36042Y387000D02*
X44250D01*
X35000Y388041D02*
X36042Y387000D01*
X28500Y392000D02*
X33958D01*
X35000Y390959D01*
X31414Y409872D02*
X32036Y409250D01*
X31286Y410000D02*
X31414Y409872D01*
Y403184D02*
Y409872D01*
X32036Y409250D02*
X44500D01*
X11000Y339000D02*
X26000D01*
X18510Y344004D02*
X18519Y343994D01*
X18500Y360000D02*
X18510Y359991D01*
Y344004D02*
Y359991D01*
X25500Y349000D02*
X26000D01*
X13500Y351000D02*
Y360000D01*
X11500Y349000D02*
X13500Y351000D01*
X11000Y349000D02*
X11500D01*
X23500Y351000D02*
Y360000D01*
Y351000D02*
X25500Y349000D01*
X171295Y375639D02*
Y389365D01*
X171304Y389374D01*
X171164Y364779D02*
Y375508D01*
X171295Y375639D01*
X171000Y353286D02*
Y364616D01*
X171164Y364779D01*
X171000Y321600D02*
Y344714D01*
X171000Y344714D02*
X171000Y344714D01*
D57*
X67948Y373250D02*
X77000D01*
X86000Y352000D02*
X86500Y352500D01*
Y372750D01*
X87000Y373250D01*
X90500Y348000D02*
X120000D01*
X86500Y352000D02*
X90500Y348000D01*
X151962Y364328D02*
Y373038D01*
Y364059D02*
Y364328D01*
X152053Y364419D01*
X162233D01*
X162593Y364779D01*
X151000Y374000D02*
X151962Y373038D01*
D58*
X211156Y38620D02*
D03*
X126000Y100000D02*
D03*
X104000Y107000D02*
D03*
X209830Y407680D02*
D03*
Y397520D02*
D03*
Y387360D02*
D03*
Y377200D02*
D03*
Y367040D02*
D03*
Y356880D02*
D03*
Y346720D02*
D03*
Y336560D02*
D03*
Y326400D02*
D03*
X199670Y407680D02*
D03*
Y397520D02*
D03*
Y387360D02*
D03*
Y377200D02*
D03*
Y367040D02*
D03*
Y356880D02*
D03*
Y346720D02*
D03*
Y336560D02*
D03*
Y326400D02*
D03*
X189510Y387360D02*
D03*
Y367040D02*
D03*
Y356880D02*
D03*
Y346720D02*
D03*
Y336560D02*
D03*
Y326400D02*
D03*
X179350Y367040D02*
D03*
Y356880D02*
D03*
Y346720D02*
D03*
Y336560D02*
D03*
X169190Y407680D02*
D03*
X159030Y387360D02*
D03*
Y377200D02*
D03*
Y356880D02*
D03*
Y346720D02*
D03*
Y336560D02*
D03*
X148870Y387360D02*
D03*
Y346720D02*
D03*
X138710Y397520D02*
D03*
Y387360D02*
D03*
X128550D02*
D03*
X118390D02*
D03*
X98070D02*
D03*
X87910Y306080D02*
D03*
X77750Y407680D02*
D03*
Y387360D02*
D03*
Y356880D02*
D03*
X67590Y397520D02*
D03*
Y306080D02*
D03*
Y295920D02*
D03*
Y285760D02*
D03*
Y275600D02*
D03*
X190545Y43935D02*
D03*
X115000Y146000D02*
D03*
X106178Y147000D02*
D03*
X115000Y139000D02*
D03*
X168000Y131000D02*
D03*
X204000Y111000D02*
D03*
X166000Y112000D02*
D03*
X201000Y120000D02*
D03*
X167000D02*
D03*
X154373Y105997D02*
D03*
X210000Y181100D02*
D03*
Y192100D02*
D03*
X76611Y127172D02*
D03*
X52102Y139442D02*
D03*
X53051Y126729D02*
D03*
X41792Y117242D02*
D03*
X39452Y130651D02*
D03*
X12000Y65000D02*
D03*
Y74000D02*
D03*
X37758Y73000D02*
D03*
X37000Y64000D02*
D03*
X206000Y52000D02*
D03*
X197000D02*
D03*
X207000Y77000D02*
D03*
X198000D02*
D03*
X204000Y40054D02*
D03*
X191000Y37000D02*
D03*
X90162Y85574D02*
D03*
X80512Y67616D02*
D03*
X106948Y62472D02*
D03*
X93057Y101595D02*
D03*
X94793Y112219D02*
D03*
X65988Y100369D02*
D03*
X66000Y112000D02*
D03*
X145027Y145180D02*
D03*
X128214Y138000D02*
D03*
X181826Y161442D02*
D03*
X148849Y161221D02*
D03*
X138262Y162104D02*
D03*
X83228D02*
D03*
X83000Y146000D02*
D03*
X91831Y146884D02*
D03*
X37000Y194600D02*
D03*
X58000D02*
D03*
X79000D02*
D03*
X100000Y194000D02*
D03*
X121000Y194600D02*
D03*
X142000D02*
D03*
X163000D02*
D03*
X184000Y194600D02*
D03*
X37000Y215600D02*
D03*
X58000D02*
D03*
X79000D02*
D03*
X100000Y215000D02*
D03*
X121000Y215600D02*
D03*
X142000D02*
D03*
X163000D02*
D03*
X184000Y215600D02*
D03*
X37000Y236600D02*
D03*
X58000D02*
D03*
X79000D02*
D03*
X100000Y236000D02*
D03*
X121000Y236600D02*
D03*
X142000D02*
D03*
X163000D02*
D03*
X184000Y236600D02*
D03*
X37000Y257000D02*
D03*
X58000D02*
D03*
X79000D02*
D03*
X100000Y256400D02*
D03*
X121000Y257000D02*
D03*
X142000D02*
D03*
X163000D02*
D03*
X184000Y257000D02*
D03*
X37000Y278600D02*
D03*
X58000D02*
D03*
X79000D02*
D03*
X100000Y278000D02*
D03*
X121000Y278600D02*
D03*
X142000D02*
D03*
X163000D02*
D03*
X184000Y278600D02*
D03*
Y299600D02*
D03*
X163000Y299600D02*
D03*
X142000D02*
D03*
X121000D02*
D03*
X100000Y299000D02*
D03*
X79000Y299600D02*
D03*
X58000D02*
D03*
X37000D02*
D03*
X210000Y203100D02*
D03*
Y214100D02*
D03*
Y236100D02*
D03*
Y258100D02*
D03*
Y302100D02*
D03*
Y313100D02*
D03*
X149024Y334175D02*
D03*
X137823Y333314D02*
D03*
X126909Y334032D02*
D03*
X17430Y401507D02*
D03*
X68713Y403287D02*
D03*
X14291Y409878D02*
D03*
X11151Y401828D02*
D03*
X53974Y359649D02*
D03*
X23386Y401023D02*
D03*
X51000Y371000D02*
D03*
X50396Y377474D02*
D03*
X31414Y403184D02*
D03*
X11000Y339000D02*
D03*
X18519Y343994D02*
D03*
X26000Y349000D02*
D03*
X11000D02*
D03*
X49915Y341352D02*
D03*
X39824Y361855D02*
D03*
X63000Y38000D02*
D03*
X176000Y44000D02*
D03*
X111000Y35000D02*
D03*
X152000Y36000D02*
D03*
X137000D02*
D03*
X123000Y35000D02*
D03*
X93000Y34000D02*
D03*
X33000Y31000D02*
D03*
Y38000D02*
D03*
X32880Y45166D02*
D03*
X33000Y51645D02*
D03*
X15000Y50312D02*
D03*
X12791Y42000D02*
D03*
X6395Y41971D02*
D03*
X6826Y50312D02*
D03*
D59*
X110000Y420000D02*
D03*
M02*
